(kicad_pcb
	(version 20260206)
	(generator "pcbnew")
	(generator_version "10.0")
	(general
		(thickness 1.6)
		(legacy_teardrops no)
	)
	(paper "A4")
	(title_block
		(title "04192023_DAF0TMB3IC0_F0TG_MB_C_brd_V02_OCP.brd")
		(comment 1 "Grand Teton / footprints 373-380 of 8354")
	)
	(layers
		(0 "F.Cu" signal "TOP")
		(4 "In1.Cu" signal "GND")
		(6 "In2.Cu" signal "IN1")
		(8 "In3.Cu" signal "GND1")
		(10 "In4.Cu" signal "IN2")
		(12 "In5.Cu" signal "GND2")
		(14 "In6.Cu" signal "IN3")
		(16 "In7.Cu" signal "GND3")
		(18 "In8.Cu" signal "VCC")
		(20 "In9.Cu" signal "VCC1")
		(22 "In10.Cu" signal "GND4")
		(24 "In11.Cu" signal "IN4")
		(26 "In12.Cu" signal "GND5")
		(28 "In13.Cu" signal "IN5")
		(30 "In14.Cu" signal "GND6")
		(32 "In15.Cu" signal "IN6")
		(34 "In16.Cu" signal "GND7")
		(2 "B.Cu" signal "BOTTOM")
		(9 "F.Adhes" user "F.Adhesive")
		(11 "B.Adhes" user "B.Adhesive")
		(13 "F.Paste" user "Package Geometry/Pastemask Top")
		(15 "B.Paste" user "Package Geometry/Pastemask Bottom")
		(5 "F.SilkS" user "Ref Des/Silkscreen Top")
		(7 "B.SilkS" user "Ref Des/Silkscreen Bottom")
		(1 "F.Mask" user "Board Geometry/Soldermask Top")
		(3 "B.Mask" user "Board Geometry/Soldermask Bottom")
		(17 "Dwgs.User" user "User.Drawings")
		(19 "Cmts.User" user "User.Comments")
		(21 "Eco1.User" user "User.Eco1")
		(23 "Eco2.User" user "User.Eco2")
		(25 "Edge.Cuts" user "Board Geometry/Outline")
		(27 "Margin" user)
		(31 "F.CrtYd" user "Package Geometry/Place Bound Top")
		(29 "B.CrtYd" user "Package Geometry/Place Bound Bottom")
		(35 "F.Fab" user "Ref Des/Assembly Top")
		(33 "B.Fab" user "Ref Des/Assembly Bottom")
	)
	(footprint ""
		(layer "F.Cu")
		(at 69.359526 -148.22678 90)
		(property "Reference" "PR398"
			(at 0 0 90)
			(layer "F.SilkS")
			(hide yes)
			(effects
				(font
					(size 1.27 1.27)
				)
			)
		)
		(property "Value" ""
			(at 0 0 90)
			(layer "F.Fab")
			(effects
				(font
					(size 1.27 1.27)
				)
			)
		)
		(duplicate_pad_numbers_are_jumpers no)
		(fp_line
			(start 0.7874 -0.4064)
			(end 0.7874 0.4064)
			(stroke
				(width 0.1524)
				(type default)
			)
			(layer "F.SilkS")
		)
		(fp_line
			(start -0.7874 -0.4064)
			(end 0.7874 -0.4064)
			(stroke
				(width 0.1524)
				(type default)
			)
			(layer "F.SilkS")
		)
		(fp_line
			(start 0.7874 0.4064)
			(end -0.7874 0.4064)
			(stroke
				(width 0.1524)
				(type default)
			)
			(layer "F.SilkS")
		)
		(fp_line
			(start -0.7874 0.4064)
			(end -0.7874 -0.4064)
			(stroke
				(width 0.1524)
				(type default)
			)
			(layer "F.SilkS")
		)
		(fp_line
			(start -0.12065 -0.305054)
			(end -0.12065 -0.2794)
			(stroke
				(width 0.1)
				(type default)
			)
			(layer "F.Fab")
		)
		(fp_line
			(start -0.67945 -0.305054)
			(end -0.12065 -0.305054)
			(stroke
				(width 0.1)
				(type default)
			)
			(layer "F.Fab")
		)
		(fp_line
			(start 0.67945 -0.3048)
			(end 0.67945 0.3048)
			(stroke
				(width 0.1)
				(type default)
			)
			(layer "F.Fab")
		)
		(fp_line
			(start 0.12065 -0.3048)
			(end 0.67945 -0.3048)
			(stroke
				(width 0.1)
				(type default)
			)
			(layer "F.Fab")
		)
		(fp_line
			(start 0.12065 -0.2794)
			(end 0.12065 -0.3048)
			(stroke
				(width 0.1)
				(type default)
			)
			(layer "F.Fab")
		)
		(fp_line
			(start -0.12065 -0.2794)
			(end 0.12065 -0.2794)
			(stroke
				(width 0.1)
				(type default)
			)
			(layer "F.Fab")
		)
		(fp_line
			(start 0.120396 0.2794)
			(end -0.12065 0.2794)
			(stroke
				(width 0.1)
				(type default)
			)
			(layer "F.Fab")
		)
		(fp_line
			(start -0.12065 0.2794)
			(end -0.12065 0.3048)
			(stroke
				(width 0.1)
				(type default)
			)
			(layer "F.Fab")
		)
		(fp_line
			(start 0.67945 0.3048)
			(end 0.120396 0.3048)
			(stroke
				(width 0.1)
				(type default)
			)
			(layer "F.Fab")
		)
		(fp_line
			(start 0.120396 0.3048)
			(end 0.120396 0.2794)
			(stroke
				(width 0.1)
				(type default)
			)
			(layer "F.Fab")
		)
		(fp_line
			(start -0.12065 0.3048)
			(end -0.67945 0.3048)
			(stroke
				(width 0.1)
				(type default)
			)
			(layer "F.Fab")
		)
		(fp_line
			(start -0.67945 0.3048)
			(end -0.67945 -0.305054)
			(stroke
				(width 0.1)
				(type default)
			)
			(layer "F.Fab")
		)
		(pad "1" smd circle
			(at -0.40005 0 90)
			(size 0 0)
			(layers "F.Cu" "F.Mask" "F.Paste")
			(net "GND")
		)
		(pad "2" smd circle
			(at 0.40005 0 90)
			(size 0 0)
			(layers "F.Cu" "F.Mask" "F.Paste")
			(net "PVDD18_S5_P1_MODE")
		)
	)
	(footprint ""
		(layer "F.Cu")
		(at 268.355318 -103.26624)
		(property "Reference" "C1506"
			(at 0 0 0)
			(layer "F.SilkS")
			(hide yes)
			(effects
				(font
					(size 1.27 1.27)
				)
			)
		)
		(property "Value" ""
			(at 0 0 0)
			(layer "F.Fab")
			(effects
				(font
					(size 1.27 1.27)
				)
			)
		)
		(duplicate_pad_numbers_are_jumpers no)
		(fp_line
			(start -0.7874 -0.4064)
			(end 0.7874 -0.4064)
			(stroke
				(width 0.1524)
				(type default)
			)
			(layer "F.SilkS")
		)
		(fp_line
			(start -0.7874 0.4064)
			(end -0.7874 -0.4064)
			(stroke
				(width 0.1524)
				(type default)
			)
			(layer "F.SilkS")
		)
		(fp_line
			(start 0.7874 -0.4064)
			(end 0.7874 0.4064)
			(stroke
				(width 0.1524)
				(type default)
			)
			(layer "F.SilkS")
		)
		(fp_line
			(start 0.7874 0.4064)
			(end -0.7874 0.4064)
			(stroke
				(width 0.1524)
				(type default)
			)
			(layer "F.SilkS")
		)
		(fp_line
			(start -0.67945 -0.305054)
			(end -0.12065 -0.305054)
			(stroke
				(width 0.1)
				(type default)
			)
			(layer "F.Fab")
		)
		(fp_line
			(start -0.67945 0.3048)
			(end -0.67945 -0.305054)
			(stroke
				(width 0.1)
				(type default)
			)
			(layer "F.Fab")
		)
		(fp_line
			(start -0.12065 -0.305054)
			(end -0.12065 -0.2794)
			(stroke
				(width 0.1)
				(type default)
			)
			(layer "F.Fab")
		)
		(fp_line
			(start -0.12065 -0.2794)
			(end 0.12065 -0.2794)
			(stroke
				(width 0.1)
				(type default)
			)
			(layer "F.Fab")
		)
		(fp_line
			(start -0.12065 0.2794)
			(end -0.12065 0.3048)
			(stroke
				(width 0.1)
				(type default)
			)
			(layer "F.Fab")
		)
		(fp_line
			(start -0.12065 0.3048)
			(end -0.67945 0.3048)
			(stroke
				(width 0.1)
				(type default)
			)
			(layer "F.Fab")
		)
		(fp_line
			(start 0.120396 0.2794)
			(end -0.12065 0.2794)
			(stroke
				(width 0.1)
				(type default)
			)
			(layer "F.Fab")
		)
		(fp_line
			(start 0.120396 0.3048)
			(end 0.120396 0.2794)
			(stroke
				(width 0.1)
				(type default)
			)
			(layer "F.Fab")
		)
		(fp_line
			(start 0.12065 -0.3048)
			(end 0.67945 -0.3048)
			(stroke
				(width 0.1)
				(type default)
			)
			(layer "F.Fab")
		)
		(fp_line
			(start 0.12065 -0.2794)
			(end 0.12065 -0.3048)
			(stroke
				(width 0.1)
				(type default)
			)
			(layer "F.Fab")
		)
		(fp_line
			(start 0.67945 -0.3048)
			(end 0.67945 0.3048)
			(stroke
				(width 0.1)
				(type default)
			)
			(layer "F.Fab")
		)
		(fp_line
			(start 0.67945 0.3048)
			(end 0.120396 0.3048)
			(stroke
				(width 0.1)
				(type default)
			)
			(layer "F.Fab")
		)
		(pad "1" smd circle
			(at -0.40005 0)
			(size 0 0)
			(layers "F.Cu" "F.Mask" "F.Paste")
			(net "P3V3_AUX")
		)
		(pad "2" smd circle
			(at 0.40005 0)
			(size 0 0)
			(layers "F.Cu" "F.Mask" "F.Paste")
			(net "GND")
		)
	)
	(footprint ""
		(layer "F.Cu")
		(at 94.899988 -22.29993)
		(property "Reference" "H93"
			(at -5.235702 -5.709666 0)
			(unlocked yes)
			(layer "F.SilkS")
			(effects
				(font
					(size 0.7874 0.5842)
					(thickness 0.1524)
				)
				(justify left)
			)
		)
		(property "Value" ""
			(at 0 0 0)
			(layer "F.Fab")
			(effects
				(font
					(size 1.27 1.27)
				)
			)
		)
		(duplicate_pad_numbers_are_jumpers no)
		(pad "1" thru_hole circle
			(at 0 0)
			(size 10.0076 10.0076)
			(drill 5.6134)
			(layers "*.Cu" "*.Mask")
			(remove_unused_layers no)
			(net "GND")
			(clearance -1.9431)
		)
	)
	(footprint ""
		(layer "F.Cu")
		(at 365.789718 -429.075342)
		(property "Reference" "R1428"
			(at 0 0 0)
			(layer "F.SilkS")
			(hide yes)
			(effects
				(font
					(size 1.27 1.27)
				)
			)
		)
		(property "Value" ""
			(at 0 0 0)
			(layer "F.Fab")
			(effects
				(font
					(size 1.27 1.27)
				)
			)
		)
		(duplicate_pad_numbers_are_jumpers no)
		(fp_line
			(start -0.32512 -0.175006)
			(end 0.32512 -0.175006)
			(stroke
				(width 0.1)
				(type default)
			)
			(layer "F.Fab")
		)
		(fp_line
			(start -0.32512 0.175006)
			(end -0.32512 -0.175006)
			(stroke
				(width 0.1)
				(type default)
			)
			(layer "F.Fab")
		)
		(fp_line
			(start 0.32512 -0.175006)
			(end 0.32512 0.175006)
			(stroke
				(width 0.1)
				(type default)
			)
			(layer "F.Fab")
		)
		(fp_line
			(start 0.32512 0.175006)
			(end -0.32512 0.175006)
			(stroke
				(width 0.1)
				(type default)
			)
			(layer "F.Fab")
		)
		(pad "1" smd rect
			(at -0.2667 0)
			(size 0.3048 0.381)
			(layers "F.Cu" "F.Mask" "F.Paste")
			(net "P1V8_CPU0_RT_1D")
		)
		(pad "2" smd rect
			(at 0.2667 0 180)
			(size 0.3048 0.381)
			(layers "F.Cu" "F.Mask" "F.Paste")
			(net "SMB_RT_CPU0_P3_ROM_MUX_1D_SCL")
		)
	)
	(footprint ""
		(layer "F.Cu")
		(at 171.196 -117.312948)
		(property "Reference" "R210"
			(at 0 0 0)
			(layer "F.SilkS")
			(hide yes)
			(effects
				(font
					(size 1.27 1.27)
				)
			)
		)
		(property "Value" ""
			(at 0 0 0)
			(layer "F.Fab")
			(effects
				(font
					(size 1.27 1.27)
				)
			)
		)
		(duplicate_pad_numbers_are_jumpers no)
		(fp_line
			(start -0.7874 -0.4064)
			(end 0.7874 -0.4064)
			(stroke
				(width 0.1524)
				(type default)
			)
			(layer "F.SilkS")
		)
		(fp_line
			(start -0.7874 0.4064)
			(end -0.7874 -0.4064)
			(stroke
				(width 0.1524)
				(type default)
			)
			(layer "F.SilkS")
		)
		(fp_line
			(start 0.7874 -0.4064)
			(end 0.7874 0.4064)
			(stroke
				(width 0.1524)
				(type default)
			)
			(layer "F.SilkS")
		)
		(fp_line
			(start 0.7874 0.4064)
			(end -0.7874 0.4064)
			(stroke
				(width 0.1524)
				(type default)
			)
			(layer "F.SilkS")
		)
		(fp_line
			(start -0.67945 -0.305054)
			(end -0.12065 -0.305054)
			(stroke
				(width 0.1)
				(type default)
			)
			(layer "F.Fab")
		)
		(fp_line
			(start -0.67945 0.3048)
			(end -0.67945 -0.305054)
			(stroke
				(width 0.1)
				(type default)
			)
			(layer "F.Fab")
		)
		(fp_line
			(start -0.12065 -0.305054)
			(end -0.12065 -0.2794)
			(stroke
				(width 0.1)
				(type default)
			)
			(layer "F.Fab")
		)
		(fp_line
			(start -0.12065 -0.2794)
			(end 0.12065 -0.2794)
			(stroke
				(width 0.1)
				(type default)
			)
			(layer "F.Fab")
		)
		(fp_line
			(start -0.12065 0.2794)
			(end -0.12065 0.3048)
			(stroke
				(width 0.1)
				(type default)
			)
			(layer "F.Fab")
		)
		(fp_line
			(start -0.12065 0.3048)
			(end -0.67945 0.3048)
			(stroke
				(width 0.1)
				(type default)
			)
			(layer "F.Fab")
		)
		(fp_line
			(start 0.120396 0.2794)
			(end -0.12065 0.2794)
			(stroke
				(width 0.1)
				(type default)
			)
			(layer "F.Fab")
		)
		(fp_line
			(start 0.120396 0.3048)
			(end 0.120396 0.2794)
			(stroke
				(width 0.1)
				(type default)
			)
			(layer "F.Fab")
		)
		(fp_line
			(start 0.12065 -0.3048)
			(end 0.67945 -0.3048)
			(stroke
				(width 0.1)
				(type default)
			)
			(layer "F.Fab")
		)
		(fp_line
			(start 0.12065 -0.2794)
			(end 0.12065 -0.3048)
			(stroke
				(width 0.1)
				(type default)
			)
			(layer "F.Fab")
		)
		(fp_line
			(start 0.67945 -0.3048)
			(end 0.67945 0.3048)
			(stroke
				(width 0.1)
				(type default)
			)
			(layer "F.Fab")
		)
		(fp_line
			(start 0.67945 0.3048)
			(end 0.120396 0.3048)
			(stroke
				(width 0.1)
				(type default)
			)
			(layer "F.Fab")
		)
		(pad "1" smd circle
			(at -0.40005 0)
			(size 0 0)
			(layers "F.Cu" "F.Mask" "F.Paste")
			(net "SMB_2_PLD_3V3AUX_SCL_R1")
		)
		(pad "2" smd circle
			(at 0.40005 0)
			(size 0 0)
			(layers "F.Cu" "F.Mask" "F.Paste")
			(net "SMB_2_PLD_3V3AUX_SCL_R2")
		)
	)
	(footprint ""
		(layer "F.Cu")
		(at 122.3772 -73.271126 180)
		(property "Reference" "PC6016"
			(at 0 0 180)
			(layer "F.SilkS")
			(hide yes)
			(effects
				(font
					(size 1.27 1.27)
				)
			)
		)
		(property "Value" ""
			(at 0 0 180)
			(layer "F.Fab")
			(effects
				(font
					(size 1.27 1.27)
				)
			)
		)
		(duplicate_pad_numbers_are_jumpers no)
		(fp_line
			(start 0.7874 0.4064)
			(end -0.7874 0.4064)
			(stroke
				(width 0.1524)
				(type default)
			)
			(layer "F.SilkS")
		)
		(fp_line
			(start 0.7874 -0.4064)
			(end 0.7874 0.4064)
			(stroke
				(width 0.1524)
				(type default)
			)
			(layer "F.SilkS")
		)
		(fp_line
			(start -0.7874 0.4064)
			(end -0.7874 -0.4064)
			(stroke
				(width 0.1524)
				(type default)
			)
			(layer "F.SilkS")
		)
		(fp_line
			(start -0.7874 -0.4064)
			(end 0.7874 -0.4064)
			(stroke
				(width 0.1524)
				(type default)
			)
			(layer "F.SilkS")
		)
		(fp_line
			(start 0.67945 0.3048)
			(end 0.120396 0.3048)
			(stroke
				(width 0.1)
				(type default)
			)
			(layer "F.Fab")
		)
		(fp_line
			(start 0.67945 -0.3048)
			(end 0.67945 0.3048)
			(stroke
				(width 0.1)
				(type default)
			)
			(layer "F.Fab")
		)
		(fp_line
			(start 0.12065 -0.2794)
			(end 0.12065 -0.3048)
			(stroke
				(width 0.1)
				(type default)
			)
			(layer "F.Fab")
		)
		(fp_line
			(start 0.12065 -0.3048)
			(end 0.67945 -0.3048)
			(stroke
				(width 0.1)
				(type default)
			)
			(layer "F.Fab")
		)
		(fp_line
			(start 0.120396 0.3048)
			(end 0.120396 0.2794)
			(stroke
				(width 0.1)
				(type default)
			)
			(layer "F.Fab")
		)
		(fp_line
			(start 0.120396 0.2794)
			(end -0.12065 0.2794)
			(stroke
				(width 0.1)
				(type default)
			)
			(layer "F.Fab")
		)
		(fp_line
			(start -0.12065 0.3048)
			(end -0.67945 0.3048)
			(stroke
				(width 0.1)
				(type default)
			)
			(layer "F.Fab")
		)
		(fp_line
			(start -0.12065 0.2794)
			(end -0.12065 0.3048)
			(stroke
				(width 0.1)
				(type default)
			)
			(layer "F.Fab")
		)
		(fp_line
			(start -0.12065 -0.2794)
			(end 0.12065 -0.2794)
			(stroke
				(width 0.1)
				(type default)
			)
			(layer "F.Fab")
		)
		(fp_line
			(start -0.12065 -0.305054)
			(end -0.12065 -0.2794)
			(stroke
				(width 0.1)
				(type default)
			)
			(layer "F.Fab")
		)
		(fp_line
			(start -0.67945 0.3048)
			(end -0.67945 -0.305054)
			(stroke
				(width 0.1)
				(type default)
			)
			(layer "F.Fab")
		)
		(fp_line
			(start -0.67945 -0.305054)
			(end -0.12065 -0.305054)
			(stroke
				(width 0.1)
				(type default)
			)
			(layer "F.Fab")
		)
		(pad "1" smd circle
			(at -0.40005 0 180)
			(size 0 0)
			(layers "F.Cu" "F.Mask" "F.Paste")
			(net "P1V2_AUX_REF")
		)
		(pad "2" smd circle
			(at 0.40005 0 180)
			(size 0 0)
			(layers "F.Cu" "F.Mask" "F.Paste")
			(net "GND")
		)
	)
	(footprint ""
		(layer "F.Cu")
		(at 18.064734 -381.6858 -90)
		(property "Reference" "PL6511"
			(at 3.3528 3.814064 90)
			(unlocked yes)
			(layer "F.SilkS")
			(effects
				(font
					(size 0.7874 0.5842)
					(thickness 0.1524)
				)
				(justify left)
			)
		)
		(property "Value" ""
			(at 0 0 270)
			(layer "F.Fab")
			(effects
				(font
					(size 1.27 1.27)
				)
			)
		)
		(duplicate_pad_numbers_are_jumpers no)
		(fp_line
			(start -3.24993 3.24993)
			(end -3.24993 2.2352)
			(stroke
				(width 0.1524)
				(type default)
			)
			(layer "F.SilkS")
		)
		(fp_line
			(start 3.24993 3.24993)
			(end -3.24993 3.24993)
			(stroke
				(width 0.1524)
				(type default)
			)
			(layer "F.SilkS")
		)
		(fp_line
			(start 3.24993 2.2352)
			(end 3.24993 3.24993)
			(stroke
				(width 0.1524)
				(type default)
			)
			(layer "F.SilkS")
		)
		(fp_line
			(start -3.24993 -2.2352)
			(end -3.24993 -3.24993)
			(stroke
				(width 0.1524)
				(type default)
			)
			(layer "F.SilkS")
		)
		(fp_line
			(start -3.24993 -3.24993)
			(end 3.24993 -3.24993)
			(stroke
				(width 0.1524)
				(type default)
			)
			(layer "F.SilkS")
		)
		(fp_line
			(start 3.24993 -3.24993)
			(end 3.24993 -2.2352)
			(stroke
				(width 0.1524)
				(type default)
			)
			(layer "F.SilkS")
		)
		(fp_line
			(start -3.24993 3.24993)
			(end -3.24993 -3.24993)
			(stroke
				(width 0.1)
				(type default)
			)
			(layer "F.Fab")
		)
		(fp_line
			(start 3.24993 3.24993)
			(end -3.24993 3.24993)
			(stroke
				(width 0.1)
				(type default)
			)
			(layer "F.Fab")
		)
		(fp_line
			(start -3.24993 -3.24993)
			(end 3.24993 -3.24993)
			(stroke
				(width 0.1)
				(type default)
			)
			(layer "F.Fab")
		)
		(fp_line
			(start 3.24993 -3.24993)
			(end 3.24993 3.24993)
			(stroke
				(width 0.1)
				(type default)
			)
			(layer "F.Fab")
		)
		(pad "1" smd rect
			(at -2.29997 0 270)
			(size 2.0066 4.2164)
			(layers "F.Cu" "F.Mask" "F.Paste")
			(net "SW_P0V9_RETIMER_CPU1_SW1")
		)
		(pad "2" smd rect
			(at 2.29997 0 270)
			(size 2.0066 4.2164)
			(layers "F.Cu" "F.Mask" "F.Paste")
			(net "P0V9_CPU1_RT_2D")
		)
	)
	(footprint ""
		(layer "F.Cu")
		(at 204.7621 -401.988782 180)
		(property "Reference" "PR1101"
			(at 0 0 180)
			(layer "F.SilkS")
			(hide yes)
			(effects
				(font
					(size 1.27 1.27)
				)
			)
		)
		(property "Value" ""
			(at 0 0 180)
			(layer "F.Fab")
			(effects
				(font
					(size 1.27 1.27)
				)
			)
		)
		(duplicate_pad_numbers_are_jumpers no)
		(fp_line
			(start 0.7874 0.4064)
			(end -0.7874 0.4064)
			(stroke
				(width 0.1524)
				(type default)
			)
			(layer "F.SilkS")
		)
		(fp_line
			(start 0.7874 -0.4064)
			(end 0.7874 0.4064)
			(stroke
				(width 0.1524)
				(type default)
			)
			(layer "F.SilkS")
		)
		(fp_line
			(start -0.7874 0.4064)
			(end -0.7874 -0.4064)
			(stroke
				(width 0.1524)
				(type default)
			)
			(layer "F.SilkS")
		)
		(fp_line
			(start -0.7874 -0.4064)
			(end 0.7874 -0.4064)
			(stroke
				(width 0.1524)
				(type default)
			)
			(layer "F.SilkS")
		)
		(fp_line
			(start 0.67945 0.3048)
			(end 0.120396 0.3048)
			(stroke
				(width 0.1)
				(type default)
			)
			(layer "F.Fab")
		)
		(fp_line
			(start 0.67945 -0.3048)
			(end 0.67945 0.3048)
			(stroke
				(width 0.1)
				(type default)
			)
			(layer "F.Fab")
		)
		(fp_line
			(start 0.12065 -0.2794)
			(end 0.12065 -0.3048)
			(stroke
				(width 0.1)
				(type default)
			)
			(layer "F.Fab")
		)
		(fp_line
			(start 0.12065 -0.3048)
			(end 0.67945 -0.3048)
			(stroke
				(width 0.1)
				(type default)
			)
			(layer "F.Fab")
		)
		(fp_line
			(start 0.120396 0.3048)
			(end 0.120396 0.2794)
			(stroke
				(width 0.1)
				(type default)
			)
			(layer "F.Fab")
		)
		(fp_line
			(start 0.120396 0.2794)
			(end -0.12065 0.2794)
			(stroke
				(width 0.1)
				(type default)
			)
			(layer "F.Fab")
		)
		(fp_line
			(start -0.12065 0.3048)
			(end -0.67945 0.3048)
			(stroke
				(width 0.1)
				(type default)
			)
			(layer "F.Fab")
		)
		(fp_line
			(start -0.12065 0.2794)
			(end -0.12065 0.3048)
			(stroke
				(width 0.1)
				(type default)
			)
			(layer "F.Fab")
		)
		(fp_line
			(start -0.12065 -0.2794)
			(end 0.12065 -0.2794)
			(stroke
				(width 0.1)
				(type default)
			)
			(layer "F.Fab")
		)
		(fp_line
			(start -0.12065 -0.305054)
			(end -0.12065 -0.2794)
			(stroke
				(width 0.1)
				(type default)
			)
			(layer "F.Fab")
		)
		(fp_line
			(start -0.67945 0.3048)
			(end -0.67945 -0.305054)
			(stroke
				(width 0.1)
				(type default)
			)
			(layer "F.Fab")
		)
		(fp_line
			(start -0.67945 -0.305054)
			(end -0.12065 -0.305054)
			(stroke
				(width 0.1)
				(type default)
			)
			(layer "F.Fab")
		)
		(pad "1" smd circle
			(at -0.40005 0 180)
			(size 0 0)
			(layers "F.Cu" "F.Mask" "F.Paste")
			(net "HSC_IMON")
		)
		(pad "2" smd circle
			(at 0.40005 0 180)
			(size 0 0)
			(layers "F.Cu" "F.Mask" "F.Paste")
			(net "AGND_HSC")
		)
	)
)
